(kicad_pcb
	(version 20260206)
	(generator "pcbnew")
	(generator_version "10.0")
	(general
		(thickness 1.6)
		(legacy_teardrops no)
	)
	(paper "A4")
	(title_block
		(title "Wiwynn_Tioga_Pass_MB.brd")
		(comment 1 "Tioga Pass / footprints 2741-2747 of 4770")
	)
	(layers
		(0 "F.Cu" signal "TOP")
		(4 "In1.Cu" signal "L2GND")
		(6 "In2.Cu" signal "L3")
		(8 "In3.Cu" signal "L4GND")
		(10 "In4.Cu" signal "L5")
		(12 "In5.Cu" signal "L6GND")
		(14 "In6.Cu" signal "L7VCC")
		(16 "In7.Cu" signal "L8VCC")
		(18 "In8.Cu" signal "L9GND")
		(20 "In9.Cu" signal "L10")
		(22 "In10.Cu" signal "L11GND")
		(24 "In11.Cu" signal "L12")
		(26 "In12.Cu" signal "L13GND")
		(2 "B.Cu" signal "BOTTOM")
		(9 "F.Adhes" user "F.Adhesive")
		(11 "B.Adhes" user "B.Adhesive")
		(13 "F.Paste" user "Package Geometry/Pastemask Top")
		(15 "B.Paste" user "Package Geometry/Pastemask Bottom")
		(5 "F.SilkS" user "Ref Des/Silkscreen Top")
		(7 "B.SilkS" user "Ref Des/Silkscreen Bottom")
		(1 "F.Mask" user "Board Geometry/Soldermask Top")
		(3 "B.Mask" user "Board Geometry/Soldermask Bottom")
		(17 "Dwgs.User" user "User.Drawings")
		(19 "Cmts.User" user "User.Comments")
		(21 "Eco1.User" user "User.Eco1")
		(23 "Eco2.User" user "User.Eco2")
		(25 "Edge.Cuts" user "Board Geometry/Outline")
		(27 "Margin" user)
		(31 "F.CrtYd" user "Package Geometry/Place Bound Top")
		(29 "B.CrtYd" user "Package Geometry/Place Bound Bottom")
		(35 "F.Fab" user "Ref Des/Assembly Top")
		(33 "B.Fab" user "Ref Des/Assembly Bottom")
	)
	(footprint ""
		(layer "B.Cu")
		(at 387.689598 -34.655506 -90)
		(property "Reference" "R7W6"
			(at 0.8382 -0.67818 270)
			(unlocked yes)
			(layer "B.SilkS")
			(effects
				(font
					(size 0.4064 0.254)
					(thickness 0.1524)
				)
				(justify left mirror)
			)
		)
		(property "Value" ""
			(at 0 0 90)
			(layer "B.Fab")
			(effects
				(font
					(size 1.27 1.27)
				)
				(justify mirror)
			)
		)
		(duplicate_pad_numbers_are_jumpers no)
		(fp_poly
			(pts
				(xy 0.2794 -0.1016) (xy -0.2794 -0.1016) (xy -0.2794 0.9906) (xy 0.2794 0.9906)
			)
			(stroke
				(width 0)
				(type default)
			)
			(fill no)
			(layer "B.CrtYd")
		)
		(fp_line
			(start -0.2794 0.9906)
			(end -0.2794 -0.1016)
			(stroke
				(width 0.1)
				(type default)
			)
			(layer "B.Fab")
		)
		(fp_line
			(start 0.2794 0.9906)
			(end -0.2794 0.9906)
			(stroke
				(width 0.1)
				(type default)
			)
			(layer "B.Fab")
		)
		(fp_line
			(start -0.2794 -0.1016)
			(end 0.2794 -0.1016)
			(stroke
				(width 0.1)
				(type default)
			)
			(layer "B.Fab")
		)
		(fp_line
			(start 0.2794 -0.1016)
			(end 0.2794 0.9906)
			(stroke
				(width 0.1)
				(type default)
			)
			(layer "B.Fab")
		)
		(pad "1" smd rect
			(at 0 0 90)
			(size 0.508 0.508)
			(layers "B.Cu" "B.Mask" "B.Paste")
			(net "FM_BATTERY_SENSE_EN_N")
		)
		(pad "2" smd rect
			(at 0 0.889 90)
			(size 0.508 0.508)
			(layers "B.Cu" "B.Mask" "B.Paste")
			(net "FM_BATTERY_SENSE_EN_R_N")
		)
		(zone
			(layer "B.Cu")
			(hatch none 0.5)
			(connect_pads
				(clearance 0)
			)
			(min_thickness 0.25)
			(keepout
				(tracks not_allowed)
				(vias allowed)
				(pads allowed)
				(copperpour not_allowed)
				(footprints allowed)
			)
			(placement
				(enabled no)
				(sheetname "")
			)
			(fill
				(thermal_gap 0.5)
				(thermal_bridge_width 0.5)
				(island_removal_mode 0)
			)
			(polygon
				(pts
					(xy 387.054598 -34.401506) (xy 387.054598 -34.909506) (xy 387.435598 -34.909506) (xy 387.435598 -34.401506)
				)
			)
		)
		(zone
			(layer "B.Cu")
			(hatch none 0.5)
			(connect_pads
				(clearance 0)
			)
			(min_thickness 0.25)
			(keepout
				(tracks allowed)
				(vias not_allowed)
				(pads allowed)
				(copperpour not_allowed)
				(footprints allowed)
			)
			(placement
				(enabled no)
				(sheetname "")
			)
			(fill
				(thermal_gap 0.5)
				(thermal_bridge_width 0.5)
				(island_removal_mode 0)
			)
			(polygon
				(pts
					(xy 387.435598 -34.401506) (xy 387.435598 -34.909506) (xy 387.054598 -34.909506) (xy 387.054598 -34.401506)
				)
			)
		)
	)
	(footprint ""
		(layer "B.Cu")
		(at 248.8565 -149.8092 -90)
		(property "Reference" "C5G60"
			(at -1.14681 0.76708 0)
			(unlocked yes)
			(layer "B.SilkS")
			(effects
				(font
					(size 0.7874 0.5842)
					(thickness 0.1524)
				)
				(justify mirror)
			)
		)
		(property "Value" ""
			(at 0 0 90)
			(layer "B.Fab")
			(effects
				(font
					(size 1.27 1.27)
				)
				(justify mirror)
			)
		)
		(duplicate_pad_numbers_are_jumpers no)
		(fp_rect
			(start 0.4953 1.6002)
			(end -0.4953 -0.2032)
			(stroke
				(width 0)
				(type default)
			)
			(fill no)
			(layer "B.CrtYd")
		)
		(fp_line
			(start -0.4953 1.6002)
			(end 0.4953 1.6002)
			(stroke
				(width 0.1)
				(type default)
			)
			(layer "B.Fab")
		)
		(fp_line
			(start 0.4953 1.6002)
			(end 0.4953 -0.2032)
			(stroke
				(width 0.1)
				(type default)
			)
			(layer "B.Fab")
		)
		(fp_line
			(start -0.4953 -0.2032)
			(end -0.4953 1.6002)
			(stroke
				(width 0.1)
				(type default)
			)
			(layer "B.Fab")
		)
		(fp_line
			(start 0.4953 -0.2032)
			(end -0.4953 -0.2032)
			(stroke
				(width 0.1)
				(type default)
			)
			(layer "B.Fab")
		)
		(pad "1" smd rect
			(at 0 0 90)
			(size 0.762 0.889)
			(layers "B.Cu" "B.Mask" "B.Paste")
			(net "PVDDQ_DEF")
		)
		(pad "2" smd rect
			(at 0 1.397 90)
			(size 0.762 0.889)
			(layers "B.Cu" "B.Mask" "B.Paste")
			(net "GND")
		)
		(zone
			(layer "B.Cu")
			(hatch none 0.5)
			(connect_pads
				(clearance 0)
			)
			(min_thickness 0.25)
			(keepout
				(tracks not_allowed)
				(vias allowed)
				(pads allowed)
				(copperpour not_allowed)
				(footprints allowed)
			)
			(placement
				(enabled no)
				(sheetname "")
			)
			(fill
				(thermal_gap 0.5)
				(thermal_bridge_width 0.5)
				(island_removal_mode 0)
			)
			(polygon
				(pts
					(xy 247.904 -149.4282) (xy 248.412 -149.4282) (xy 248.412 -150.1902) (xy 247.904 -150.1902)
				)
			)
		)
	)
	(footprint ""
		(layer "B.Cu")
		(at 389.509 -104.4702 -90)
		(property "Reference" "C2N20"
			(at 0 0 90)
			(layer "B.SilkS")
			(hide yes)
			(effects
				(font
					(size 1.27 1.27)
				)
				(justify mirror)
			)
		)
		(property "Value" ""
			(at 0 0 90)
			(layer "B.Fab")
			(effects
				(font
					(size 1.27 1.27)
				)
				(justify mirror)
			)
		)
		(duplicate_pad_numbers_are_jumpers no)
		(fp_rect
			(start 0.2794 0.9144)
			(end -0.2794 -0.1143)
			(stroke
				(width 0)
				(type default)
			)
			(fill no)
			(layer "B.CrtYd")
		)
		(fp_line
			(start -0.2794 0.9144)
			(end 0.2794 0.9144)
			(stroke
				(width 0.1)
				(type default)
			)
			(layer "B.Fab")
		)
		(fp_line
			(start 0.2794 0.9144)
			(end 0.2794 -0.1143)
			(stroke
				(width 0.1)
				(type default)
			)
			(layer "B.Fab")
		)
		(fp_line
			(start -0.2794 -0.1143)
			(end -0.2794 0.9144)
			(stroke
				(width 0.1)
				(type default)
			)
			(layer "B.Fab")
		)
		(fp_line
			(start 0.2794 -0.1143)
			(end -0.2794 -0.1143)
			(stroke
				(width 0.1)
				(type default)
			)
			(layer "B.Fab")
		)
		(pad "1" smd custom
			(at 0 0 180)
			(size 0.10414 0.10414)
			(layers "B.Cu" "B.Mask" "B.Paste")
			(net "P3V3_STBY")
			(options
				(clearance outline)
				(anchor circle)
			)
			(primitives
				(gr_poly
					(pts
						(xy -0.20828 -0.08636) (xy -0.20828 0.08636) (xy -0.08636 0.20828) (xy 0.086614 0.20828) (xy 0.20828 0.086614)
						(xy 0.20828 -0.08636) (xy 0.08636 -0.20828) (xy -0.08636 -0.20828)
					)
					(width 0)
					(fill yes)
				)
			)
		)
		(pad "2" smd custom
			(at 0 0.8001 180)
			(size 0.10414 0.10414)
			(layers "B.Cu" "B.Mask" "B.Paste")
			(net "GND")
			(options
				(clearance outline)
				(anchor circle)
			)
			(primitives
				(gr_poly
					(pts
						(xy -0.20828 -0.08636) (xy -0.20828 0.08636) (xy -0.08636 0.20828) (xy 0.086614 0.20828) (xy 0.20828 0.086614)
						(xy 0.20828 -0.08636) (xy 0.08636 -0.20828) (xy -0.08636 -0.20828)
					)
					(width 0)
					(fill yes)
				)
			)
		)
		(zone
			(layer "B.Cu")
			(hatch none 0.5)
			(connect_pads
				(clearance 0)
			)
			(min_thickness 0.25)
			(keepout
				(tracks allowed)
				(vias not_allowed)
				(pads allowed)
				(copperpour not_allowed)
				(footprints allowed)
			)
			(placement
				(enabled no)
				(sheetname "")
			)
			(fill
				(thermal_gap 0.5)
				(thermal_bridge_width 0.5)
				(island_removal_mode 0)
			)
			(polygon
				(pts
					(xy 389.29945 -104.38257) (xy 388.91845 -104.38257) (xy 388.91845 -104.55783) (xy 389.29945 -104.558084)
				)
			)
		)
		(zone
			(layer "B.Cu")
			(hatch none 0.5)
			(connect_pads
				(clearance 0)
			)
			(min_thickness 0.25)
			(keepout
				(tracks not_allowed)
				(vias allowed)
				(pads allowed)
				(copperpour not_allowed)
				(footprints allowed)
			)
			(placement
				(enabled no)
				(sheetname "")
			)
			(fill
				(thermal_gap 0.5)
				(thermal_bridge_width 0.5)
				(island_removal_mode 0)
			)
			(polygon
				(pts
					(xy 389.29945 -104.38257) (xy 388.91845 -104.38257) (xy 388.91845 -104.55783) (xy 389.29945 -104.558084)
				)
			)
		)
	)
	(footprint ""
		(layer "B.Cu")
		(at 94.292928 -144.987772 90)
		(property "Reference" "C8L11"
			(at 0 0 90)
			(layer "B.SilkS")
			(hide yes)
			(effects
				(font
					(size 1.27 1.27)
				)
				(justify mirror)
			)
		)
		(property "Value" ""
			(at 0 0 90)
			(layer "B.Fab")
			(effects
				(font
					(size 1.27 1.27)
				)
				(justify mirror)
			)
		)
		(duplicate_pad_numbers_are_jumpers no)
		(fp_poly
			(pts
				(xy 0.7239 -0.2159) (xy -0.7239 -0.2159) (xy -0.7239 1.9939) (xy 0.7239 1.9939)
			)
			(stroke
				(width 0)
				(type default)
			)
			(fill no)
			(layer "B.CrtYd")
		)
		(fp_line
			(start 0.7239 -0.2159)
			(end 0.7239 1.9939)
			(stroke
				(width 0.1)
				(type default)
			)
			(layer "B.Fab")
		)
		(fp_line
			(start -0.7239 -0.2159)
			(end 0.7239 -0.2159)
			(stroke
				(width 0.1)
				(type default)
			)
			(layer "B.Fab")
		)
		(fp_line
			(start 0.7239 1.9939)
			(end -0.7239 1.9939)
			(stroke
				(width 0.1)
				(type default)
			)
			(layer "B.Fab")
		)
		(fp_line
			(start -0.7239 1.9939)
			(end -0.7239 -0.2159)
			(stroke
				(width 0.1)
				(type default)
			)
			(layer "B.Fab")
		)
		(pad "1" smd rect
			(at 0 0 270)
			(size 1.27 1.016)
			(layers "B.Cu" "B.Mask" "B.Paste")
			(net "PVDDQ_KLM")
		)
		(pad "2" smd rect
			(at 0 1.778 270)
			(size 1.27 1.016)
			(layers "B.Cu" "B.Mask" "B.Paste")
			(net "GND")
		)
		(zone
			(layer "B.Cu")
			(hatch none 0.5)
			(connect_pads
				(clearance 0)
			)
			(min_thickness 0.25)
			(keepout
				(tracks not_allowed)
				(vias allowed)
				(pads allowed)
				(copperpour not_allowed)
				(footprints allowed)
			)
			(placement
				(enabled no)
				(sheetname "")
			)
			(fill
				(thermal_gap 0.5)
				(thermal_bridge_width 0.5)
				(island_removal_mode 0)
			)
			(polygon
				(pts
					(xy 94.800928 -145.622772) (xy 94.800928 -144.352772) (xy 95.562928 -144.352772) (xy 95.562928 -145.622772)
				)
			)
		)
	)
	(footprint ""
		(layer "B.Cu")
		(at 353.654614 -122.662442 -90)
		(property "Reference" "R777"
			(at 0.8382 -0.67818 270)
			(unlocked yes)
			(layer "B.SilkS")
			(effects
				(font
					(size 0.4064 0.254)
					(thickness 0.1524)
				)
				(justify left mirror)
			)
		)
		(property "Value" ""
			(at 0 0 90)
			(layer "B.Fab")
			(effects
				(font
					(size 1.27 1.27)
				)
				(justify mirror)
			)
		)
		(duplicate_pad_numbers_are_jumpers no)
		(fp_poly
			(pts
				(xy 0.2794 -0.1016) (xy -0.2794 -0.1016) (xy -0.2794 0.9906) (xy 0.2794 0.9906)
			)
			(stroke
				(width 0)
				(type default)
			)
			(fill no)
			(layer "B.CrtYd")
		)
		(fp_line
			(start -0.2794 0.9906)
			(end -0.2794 -0.1016)
			(stroke
				(width 0.1)
				(type default)
			)
			(layer "B.Fab")
		)
		(fp_line
			(start 0.2794 0.9906)
			(end -0.2794 0.9906)
			(stroke
				(width 0.1)
				(type default)
			)
			(layer "B.Fab")
		)
		(fp_line
			(start -0.2794 -0.1016)
			(end 0.2794 -0.1016)
			(stroke
				(width 0.1)
				(type default)
			)
			(layer "B.Fab")
		)
		(fp_line
			(start 0.2794 -0.1016)
			(end 0.2794 0.9906)
			(stroke
				(width 0.1)
				(type default)
			)
			(layer "B.Fab")
		)
		(pad "1" smd rect
			(at 0 0 90)
			(size 0.508 0.508)
			(layers "B.Cu" "B.Mask" "B.Paste")
			(net "P3E_CPU0_PE1_PCH_RXP<12>")
		)
		(pad "2" smd rect
			(at 0 0.889 90)
			(size 0.508 0.508)
			(layers "B.Cu" "B.Mask" "B.Paste")
			(net "P3E_CPU0_PE1_PCH_CON_RXP<12>")
		)
		(zone
			(layer "B.Cu")
			(hatch none 0.5)
			(connect_pads
				(clearance 0)
			)
			(min_thickness 0.25)
			(keepout
				(tracks not_allowed)
				(vias allowed)
				(pads allowed)
				(copperpour not_allowed)
				(footprints allowed)
			)
			(placement
				(enabled no)
				(sheetname "")
			)
			(fill
				(thermal_gap 0.5)
				(thermal_bridge_width 0.5)
				(island_removal_mode 0)
			)
			(polygon
				(pts
					(xy 353.019614 -122.408442) (xy 353.019614 -122.916442) (xy 353.400614 -122.916442) (xy 353.400614 -122.408442)
				)
			)
		)
		(zone
			(layer "B.Cu")
			(hatch none 0.5)
			(connect_pads
				(clearance 0)
			)
			(min_thickness 0.25)
			(keepout
				(tracks allowed)
				(vias not_allowed)
				(pads allowed)
				(copperpour not_allowed)
				(footprints allowed)
			)
			(placement
				(enabled no)
				(sheetname "")
			)
			(fill
				(thermal_gap 0.5)
				(thermal_bridge_width 0.5)
				(island_removal_mode 0)
			)
			(polygon
				(pts
					(xy 353.400614 -122.408442) (xy 353.400614 -122.916442) (xy 353.019614 -122.916442) (xy 353.019614 -122.408442)
				)
			)
		)
	)
	(footprint ""
		(layer "B.Cu")
		(at 45.212 -57.023 -90)
		(property "Reference" "C9R9"
			(at 0.15367 -3.556 0)
			(unlocked yes)
			(layer "B.SilkS")
			(effects
				(font
					(size 0.7874 0.5842)
					(thickness 0.1524)
				)
				(justify mirror)
			)
		)
		(property "Value" ""
			(at 0 0 90)
			(layer "B.Fab")
			(effects
				(font
					(size 1.27 1.27)
				)
				(justify mirror)
			)
		)
		(duplicate_pad_numbers_are_jumpers no)
		(fp_line
			(start -2.286 7.366)
			(end -1.600708 7.366)
			(stroke
				(width 0.1524)
				(type default)
			)
			(layer "B.SilkS")
		)
		(fp_line
			(start -2.286 7.366)
			(end -2.286 1.63195)
			(stroke
				(width 0.1524)
				(type default)
			)
			(layer "B.SilkS")
		)
		(fp_line
			(start 2.286 7.366)
			(end 1.60147 7.366)
			(stroke
				(width 0.1524)
				(type default)
			)
			(layer "B.SilkS")
		)
		(fp_line
			(start 2.286 7.366)
			(end 2.286 1.632712)
			(stroke
				(width 0.1524)
				(type default)
			)
			(layer "B.SilkS")
		)
		(fp_line
			(start -2.504948 1.633728)
			(end -1.6002 1.633728)
			(stroke
				(width 0.1524)
				(type default)
			)
			(layer "B.SilkS")
		)
		(fp_line
			(start 2.563114 1.633728)
			(end 1.6002 1.633728)
			(stroke
				(width 0.1524)
				(type default)
			)
			(layer "B.SilkS")
		)
		(fp_line
			(start -2.504948 -1.616456)
			(end -2.504948 1.633728)
			(stroke
				(width 0.1524)
				(type default)
			)
			(layer "B.SilkS")
		)
		(fp_line
			(start -1.6002 -1.616456)
			(end -2.504948 -1.616456)
			(stroke
				(width 0.1524)
				(type default)
			)
			(layer "B.SilkS")
		)
		(fp_line
			(start 1.6002 -1.616456)
			(end 2.563114 -1.616456)
			(stroke
				(width 0.1524)
				(type default)
			)
			(layer "B.SilkS")
		)
		(fp_line
			(start 2.563114 -1.616456)
			(end 2.563114 1.633728)
			(stroke
				(width 0.1524)
				(type default)
			)
			(layer "B.SilkS")
		)
		(fp_rect
			(start 2.286 7.366)
			(end -2.286 -0.254)
			(stroke
				(width 0)
				(type default)
			)
			(fill no)
			(layer "B.CrtYd")
		)
		(fp_line
			(start -2.286 7.366)
			(end 2.286 7.366)
			(stroke
				(width 0.1)
				(type default)
			)
			(layer "B.Fab")
		)
		(fp_line
			(start 2.286 7.366)
			(end 2.286 -0.254)
			(stroke
				(width 0.1)
				(type default)
			)
			(layer "B.Fab")
		)
		(fp_line
			(start -2.286 -0.254)
			(end -2.286 7.366)
			(stroke
				(width 0.1)
				(type default)
			)
			(layer "B.Fab")
		)
		(fp_line
			(start 2.286 -0.254)
			(end -2.286 -0.254)
			(stroke
				(width 0.1)
				(type default)
			)
			(layer "B.Fab")
		)
		(pad "1" smd rect
			(at 0 0 90)
			(size 2.54 3.048)
			(layers "B.Cu" "B.Mask" "B.Paste")
			(net "PVCCIN_CPU1")
		)
		(pad "2" smd rect
			(at 0 7.112 90)
			(size 2.54 3.048)
			(layers "B.Cu" "B.Mask" "B.Paste")
			(net "GND")
		)
	)
	(footprint ""
		(layer "B.Cu")
		(at 169.6466 -142.8242 90)
		(property "Reference" "C6L8"
			(at -3.15087 3.4544 0)
			(unlocked yes)
			(layer "B.SilkS")
			(effects
				(font
					(size 0.7874 0.5842)
					(thickness 0.1524)
				)
				(justify left mirror)
			)
		)
		(property "Value" ""
			(at 0 0 90)
			(layer "B.Fab")
			(effects
				(font
					(size 1.27 1.27)
				)
				(justify mirror)
			)
		)
		(duplicate_pad_numbers_are_jumpers no)
		(fp_line
			(start 2.032 -1.524)
			(end 2.032 1.524)
			(stroke
				(width 0.1524)
				(type default)
			)
			(layer "B.SilkS")
		)
		(fp_line
			(start 1.7272 -1.524)
			(end 2.032 -1.524)
			(stroke
				(width 0.1524)
				(type default)
			)
			(layer "B.SilkS")
		)
		(fp_line
			(start -1.7272 -1.524)
			(end -2.032 -1.524)
			(stroke
				(width 0.1524)
				(type default)
			)
			(layer "B.SilkS")
		)
		(fp_line
			(start -2.032 -1.524)
			(end -2.032 1.524)
			(stroke
				(width 0.1524)
				(type default)
			)
			(layer "B.SilkS")
		)
		(fp_line
			(start 2.2987 -0.2413)
			(end 2.2987 7.3533)
			(stroke
				(width 0.1524)
				(type default)
			)
			(layer "B.SilkS")
		)
		(fp_line
			(start 2.032 -0.2413)
			(end 2.2987 -0.2413)
			(stroke
				(width 0.1524)
				(type default)
			)
			(layer "B.SilkS")
		)
		(fp_line
			(start -2.2987 -0.2413)
			(end -2.032 -0.2413)
			(stroke
				(width 0.1524)
				(type default)
			)
			(layer "B.SilkS")
		)
		(fp_line
			(start 2.032 1.524)
			(end 1.7272 1.524)
			(stroke
				(width 0.1524)
				(type default)
			)
			(layer "B.SilkS")
		)
		(fp_line
			(start -2.032 1.524)
			(end -1.7272 1.524)
			(stroke
				(width 0.1524)
				(type default)
			)
			(layer "B.SilkS")
		)
		(fp_line
			(start 2.2987 7.3533)
			(end 1.7272 7.3533)
			(stroke
				(width 0.1524)
				(type default)
			)
			(layer "B.SilkS")
		)
		(fp_line
			(start -1.7272 7.3533)
			(end -2.2987 7.3533)
			(stroke
				(width 0.1524)
				(type default)
			)
			(layer "B.SilkS")
		)
		(fp_line
			(start -2.2987 7.3533)
			(end -2.2987 -0.2413)
			(stroke
				(width 0.1524)
				(type default)
			)
			(layer "B.SilkS")
		)
		(fp_poly
			(pts
				(xy 2.2987 -0.2413) (xy -2.2987 -0.2413) (xy -2.2987 7.3533) (xy 2.2987 7.3533)
			)
			(stroke
				(width 0)
				(type default)
			)
			(fill no)
			(layer "B.CrtYd")
		)
		(fp_line
			(start 2.2987 -0.2413)
			(end -2.2987 -0.2413)
			(stroke
				(width 0.1)
				(type default)
			)
			(layer "B.Fab")
		)
		(fp_line
			(start -2.2987 -0.2413)
			(end -2.2987 7.3533)
			(stroke
				(width 0.1)
				(type default)
			)
			(layer "B.Fab")
		)
		(fp_line
			(start 2.2987 7.3533)
			(end 2.2987 -0.2413)
			(stroke
				(width 0.1)
				(type default)
			)
			(layer "B.Fab")
		)
		(fp_line
			(start -2.2987 7.3533)
			(end 2.2987 7.3533)
			(stroke
				(width 0.1)
				(type default)
			)
			(layer "B.Fab")
		)
		(pad "1" smd rect
			(at 0 0 270)
			(size 2.54 3.048)
			(layers "B.Cu" "B.Mask" "B.Paste")
			(net "PVPP_KLM")
		)
		(pad "2" smd rect
			(at 0 7.112 270)
			(size 2.54 3.048)
			(layers "B.Cu" "B.Mask" "B.Paste")
			(net "GND")
		)
	)
)
